(kicad_pcb
	(version 20260206)
	(generator "pcbnew")
	(generator_version "10.0")
	(general
		(thickness 1.6)
		(legacy_teardrops no)
	)
	(paper "A4")
	(title_block
		(title "01162023_DA0F0TEBIF0_F0T_Expander_BD_F_brd_V02_OCP.brd")
		(comment 1 "Grand Teton / footprints 8765-8771 of 9728")
	)
	(layers
		(0 "F.Cu" signal "TOP")
		(4 "In1.Cu" signal "GND")
		(6 "In2.Cu" signal "VCC")
		(8 "In3.Cu" signal "VCC1")
		(10 "In4.Cu" signal "GND1")
		(12 "In5.Cu" signal "IN1")
		(14 "In6.Cu" signal "GND2")
		(16 "In7.Cu" signal "IN2")
		(18 "In8.Cu" signal "GND3")
		(20 "In9.Cu" signal "IN3")
		(22 "In10.Cu" signal "GND4")
		(24 "In11.Cu" signal "IN4")
		(26 "In12.Cu" signal "GND5")
		(28 "In13.Cu" signal "IN5")
		(30 "In14.Cu" signal "GND6")
		(32 "In15.Cu" signal "IN6")
		(34 "In16.Cu" signal "GND7")
		(2 "B.Cu" signal "BOTTOM")
		(9 "F.Adhes" user "F.Adhesive")
		(11 "B.Adhes" user "B.Adhesive")
		(13 "F.Paste" user "Package Geometry/Pastemask Top")
		(15 "B.Paste" user "Package Geometry/Pastemask Bottom")
		(5 "F.SilkS" user "Ref Des/Silkscreen Top")
		(7 "B.SilkS" user "Ref Des/Silkscreen Bottom")
		(1 "F.Mask" user "Board Geometry/Soldermask Top")
		(3 "B.Mask" user "Board Geometry/Soldermask Bottom")
		(17 "Dwgs.User" user "User.Drawings")
		(19 "Cmts.User" user "User.Comments")
		(21 "Eco1.User" user "User.Eco1")
		(23 "Eco2.User" user "User.Eco2")
		(25 "Edge.Cuts" user "Board Geometry/Outline")
		(27 "Margin" user)
		(31 "F.CrtYd" user "Package Geometry/Place Bound Top")
		(29 "B.CrtYd" user "Package Geometry/Place Bound Bottom")
		(35 "F.Fab" user "Ref Des/Assembly Top")
		(33 "B.Fab" user "Ref Des/Assembly Bottom")
	)
	(footprint ""
		(layer "B.Cu")
		(at 404.149814 -303.499774 -90)
		(property "Reference" "C3431"
			(at 0 0 90)
			(layer "B.SilkS")
			(hide yes)
			(effects
				(font
					(size 1.27 1.27)
				)
				(justify mirror)
			)
		)
		(property "Value" ""
			(at 0 0 90)
			(layer "B.Fab")
			(effects
				(font
					(size 1.27 1.27)
				)
				(justify mirror)
			)
		)
		(duplicate_pad_numbers_are_jumpers no)
		(fp_line
			(start -0.299974 0.150114)
			(end 0.299974 0.150114)
			(stroke
				(width 0.1)
				(type default)
			)
			(layer "B.Fab")
		)
		(fp_line
			(start 0.299974 0.150114)
			(end 0.299974 -0.150114)
			(stroke
				(width 0.1)
				(type default)
			)
			(layer "B.Fab")
		)
		(fp_line
			(start -0.299974 -0.150114)
			(end -0.299974 0.150114)
			(stroke
				(width 0.1)
				(type default)
			)
			(layer "B.Fab")
		)
		(fp_line
			(start 0.299974 -0.150114)
			(end -0.299974 -0.150114)
			(stroke
				(width 0.1)
				(type default)
			)
			(layer "B.Fab")
		)
		(pad "1" smd rect
			(at 0.2667 0 90)
			(size 0.3048 0.381)
			(layers "B.Cu" "B.Mask" "B.Paste")
			(net "P1V25_PEX3")
		)
		(pad "2" smd rect
			(at -0.2667 0 90)
			(size 0.3048 0.381)
			(layers "B.Cu" "B.Mask" "B.Paste")
			(net "GND")
		)
	)
	(footprint ""
		(layer "B.Cu")
		(at 289.630104 -295.221914)
		(property "Reference" "C1610"
			(at 0 0 0)
			(layer "B.SilkS")
			(hide yes)
			(effects
				(font
					(size 1.27 1.27)
				)
				(justify mirror)
			)
		)
		(property "Value" ""
			(at 0 0 0)
			(layer "B.Fab")
			(effects
				(font
					(size 1.27 1.27)
				)
				(justify mirror)
			)
		)
		(duplicate_pad_numbers_are_jumpers no)
		(fp_line
			(start -1.2954 -0.5842)
			(end -1.2954 0.5842)
			(stroke
				(width 0.1524)
				(type default)
			)
			(layer "B.SilkS")
		)
		(fp_line
			(start -1.2954 0.5842)
			(end 1.2954 0.5842)
			(stroke
				(width 0.1524)
				(type default)
			)
			(layer "B.SilkS")
		)
		(fp_line
			(start 1.2954 -0.5842)
			(end -1.2954 -0.5842)
			(stroke
				(width 0.1524)
				(type default)
			)
			(layer "B.SilkS")
		)
		(fp_line
			(start 1.2954 0.5842)
			(end 1.2954 -0.5842)
			(stroke
				(width 0.1524)
				(type default)
			)
			(layer "B.SilkS")
		)
		(fp_line
			(start -1.1938 -0.4064)
			(end -1.1938 0.4064)
			(stroke
				(width 0.1)
				(type default)
			)
			(layer "B.Fab")
		)
		(fp_line
			(start -1.1938 0.4064)
			(end -0.8636 0.4064)
			(stroke
				(width 0.1)
				(type default)
			)
			(layer "B.Fab")
		)
		(fp_line
			(start -0.8636 -0.4572)
			(end -0.8636 -0.4064)
			(stroke
				(width 0.1)
				(type default)
			)
			(layer "B.Fab")
		)
		(fp_line
			(start -0.8636 -0.4064)
			(end -1.1938 -0.4064)
			(stroke
				(width 0.1)
				(type default)
			)
			(layer "B.Fab")
		)
		(fp_line
			(start -0.8636 0.4064)
			(end -0.8636 0.4572)
			(stroke
				(width 0.1)
				(type default)
			)
			(layer "B.Fab")
		)
		(fp_line
			(start -0.8636 0.4572)
			(end 0.8636 0.4572)
			(stroke
				(width 0.1)
				(type default)
			)
			(layer "B.Fab")
		)
		(fp_line
			(start 0.8636 -0.4572)
			(end -0.8636 -0.4572)
			(stroke
				(width 0.1)
				(type default)
			)
			(layer "B.Fab")
		)
		(fp_line
			(start 0.8636 -0.4064)
			(end 0.8636 -0.4572)
			(stroke
				(width 0.1)
				(type default)
			)
			(layer "B.Fab")
		)
		(fp_line
			(start 0.8636 0.4064)
			(end 1.1938 0.4064)
			(stroke
				(width 0.1)
				(type default)
			)
			(layer "B.Fab")
		)
		(fp_line
			(start 0.8636 0.4572)
			(end 0.8636 0.4064)
			(stroke
				(width 0.1)
				(type default)
			)
			(layer "B.Fab")
		)
		(fp_line
			(start 1.1938 -0.4064)
			(end 0.8636 -0.4064)
			(stroke
				(width 0.1)
				(type default)
			)
			(layer "B.Fab")
		)
		(fp_line
			(start 1.1938 0.4064)
			(end 1.1938 -0.4064)
			(stroke
				(width 0.1)
				(type default)
			)
			(layer "B.Fab")
		)
		(pad "1" smd rect
			(at 0.7366 0 270)
			(size 0.7112 0.8128)
			(layers "B.Cu" "B.Mask" "B.Paste")
			(net "P0V8_PEX2")
		)
		(pad "2" smd rect
			(at -0.7366 0 270)
			(size 0.7112 0.8128)
			(layers "B.Cu" "B.Mask" "B.Paste")
			(net "GND")
		)
	)
	(footprint ""
		(layer "B.Cu")
		(at 460.169006 -284.375606 180)
		(property "Reference" "PC274"
			(at 0 0 0)
			(layer "B.SilkS")
			(hide yes)
			(effects
				(font
					(size 1.27 1.27)
				)
				(justify mirror)
			)
		)
		(property "Value" ""
			(at 0 0 0)
			(layer "B.Fab")
			(effects
				(font
					(size 1.27 1.27)
				)
				(justify mirror)
			)
		)
		(duplicate_pad_numbers_are_jumpers no)
		(fp_line
			(start 1.524 0.762)
			(end 1.524 -0.762)
			(stroke
				(width 0.1524)
				(type default)
			)
			(layer "B.SilkS")
		)
		(fp_line
			(start 1.524 -0.762)
			(end -1.524 -0.762)
			(stroke
				(width 0.1524)
				(type default)
			)
			(layer "B.SilkS")
		)
		(fp_line
			(start -1.524 0.762)
			(end 1.524 0.762)
			(stroke
				(width 0.1524)
				(type default)
			)
			(layer "B.SilkS")
		)
		(fp_line
			(start -1.524 -0.762)
			(end -1.524 0.762)
			(stroke
				(width 0.1524)
				(type default)
			)
			(layer "B.SilkS")
		)
		(fp_line
			(start 1.1049 0.724916)
			(end -1.1049 0.724916)
			(stroke
				(width 0.1)
				(type default)
			)
			(layer "B.Fab")
		)
		(fp_line
			(start 1.1049 -0.724916)
			(end 1.1049 0.724916)
			(stroke
				(width 0.1)
				(type default)
			)
			(layer "B.Fab")
		)
		(fp_line
			(start -1.1049 0.724916)
			(end -1.1049 -0.724916)
			(stroke
				(width 0.1)
				(type default)
			)
			(layer "B.Fab")
		)
		(fp_line
			(start -1.1049 -0.724916)
			(end 1.1049 -0.724916)
			(stroke
				(width 0.1)
				(type default)
			)
			(layer "B.Fab")
		)
		(pad "1" smd rect
			(at 0.889 0 180)
			(size 1.016 1.27)
			(layers "B.Cu" "B.Mask" "B.Paste")
			(net "P1V25_PEX3_R")
		)
		(pad "2" smd rect
			(at -0.889 0 180)
			(size 1.016 1.27)
			(layers "B.Cu" "B.Mask" "B.Paste")
			(net "GND")
		)
	)
	(footprint ""
		(layer "B.Cu")
		(at 297.10126 -305.399948 -90)
		(property "Reference" "C3302"
			(at 0 0 90)
			(layer "B.SilkS")
			(hide yes)
			(effects
				(font
					(size 1.27 1.27)
				)
				(justify mirror)
			)
		)
		(property "Value" ""
			(at 0 0 90)
			(layer "B.Fab")
			(effects
				(font
					(size 1.27 1.27)
				)
				(justify mirror)
			)
		)
		(duplicate_pad_numbers_are_jumpers no)
		(fp_line
			(start -0.299974 0.150114)
			(end 0.299974 0.150114)
			(stroke
				(width 0.1)
				(type default)
			)
			(layer "B.Fab")
		)
		(fp_line
			(start 0.299974 0.150114)
			(end 0.299974 -0.150114)
			(stroke
				(width 0.1)
				(type default)
			)
			(layer "B.Fab")
		)
		(fp_line
			(start -0.299974 -0.150114)
			(end -0.299974 0.150114)
			(stroke
				(width 0.1)
				(type default)
			)
			(layer "B.Fab")
		)
		(fp_line
			(start 0.299974 -0.150114)
			(end -0.299974 -0.150114)
			(stroke
				(width 0.1)
				(type default)
			)
			(layer "B.Fab")
		)
		(pad "1" smd rect
			(at 0.2667 0 90)
			(size 0.3048 0.381)
			(layers "B.Cu" "B.Mask" "B.Paste")
			(net "P1V25_SERDES_VDDPLL_PEX2")
		)
		(pad "2" smd rect
			(at -0.2667 0 90)
			(size 0.3048 0.381)
			(layers "B.Cu" "B.Mask" "B.Paste")
			(net "GND")
		)
	)
	(footprint ""
		(layer "B.Cu")
		(at 224.675192 -277.73503 180)
		(property "Reference" "C4289"
			(at 0 0 0)
			(layer "B.SilkS")
			(hide yes)
			(effects
				(font
					(size 1.27 1.27)
				)
				(justify mirror)
			)
		)
		(property "Value" ""
			(at 0 0 0)
			(layer "B.Fab")
			(effects
				(font
					(size 1.27 1.27)
				)
				(justify mirror)
			)
		)
		(duplicate_pad_numbers_are_jumpers no)
		(fp_line
			(start 1.2954 0.5842)
			(end 1.2954 -0.5842)
			(stroke
				(width 0.1524)
				(type default)
			)
			(layer "B.SilkS")
		)
		(fp_line
			(start 1.2954 -0.5842)
			(end -1.2954 -0.5842)
			(stroke
				(width 0.1524)
				(type default)
			)
			(layer "B.SilkS")
		)
		(fp_line
			(start -1.2954 0.5842)
			(end 1.2954 0.5842)
			(stroke
				(width 0.1524)
				(type default)
			)
			(layer "B.SilkS")
		)
		(fp_line
			(start -1.2954 -0.5842)
			(end -1.2954 0.5842)
			(stroke
				(width 0.1524)
				(type default)
			)
			(layer "B.SilkS")
		)
		(fp_line
			(start 1.1938 0.4064)
			(end 1.1938 -0.4064)
			(stroke
				(width 0.1)
				(type default)
			)
			(layer "B.Fab")
		)
		(fp_line
			(start 1.1938 -0.4064)
			(end 0.8636 -0.4064)
			(stroke
				(width 0.1)
				(type default)
			)
			(layer "B.Fab")
		)
		(fp_line
			(start 0.8636 0.4572)
			(end 0.8636 0.4064)
			(stroke
				(width 0.1)
				(type default)
			)
			(layer "B.Fab")
		)
		(fp_line
			(start 0.8636 0.4064)
			(end 1.1938 0.4064)
			(stroke
				(width 0.1)
				(type default)
			)
			(layer "B.Fab")
		)
		(fp_line
			(start 0.8636 -0.4064)
			(end 0.8636 -0.4572)
			(stroke
				(width 0.1)
				(type default)
			)
			(layer "B.Fab")
		)
		(fp_line
			(start 0.8636 -0.4572)
			(end -0.8636 -0.4572)
			(stroke
				(width 0.1)
				(type default)
			)
			(layer "B.Fab")
		)
		(fp_line
			(start -0.8636 0.4572)
			(end 0.8636 0.4572)
			(stroke
				(width 0.1)
				(type default)
			)
			(layer "B.Fab")
		)
		(fp_line
			(start -0.8636 0.4064)
			(end -0.8636 0.4572)
			(stroke
				(width 0.1)
				(type default)
			)
			(layer "B.Fab")
		)
		(fp_line
			(start -0.8636 -0.4064)
			(end -1.1938 -0.4064)
			(stroke
				(width 0.1)
				(type default)
			)
			(layer "B.Fab")
		)
		(fp_line
			(start -0.8636 -0.4572)
			(end -0.8636 -0.4064)
			(stroke
				(width 0.1)
				(type default)
			)
			(layer "B.Fab")
		)
		(fp_line
			(start -1.1938 0.4064)
			(end -0.8636 0.4064)
			(stroke
				(width 0.1)
				(type default)
			)
			(layer "B.Fab")
		)
		(fp_line
			(start -1.1938 -0.4064)
			(end -1.1938 0.4064)
			(stroke
				(width 0.1)
				(type default)
			)
			(layer "B.Fab")
		)
		(pad "1" smd rect
			(at 0.7366 0 90)
			(size 0.7112 0.8128)
			(layers "B.Cu" "B.Mask" "B.Paste")
			(net "P1V25_PEX1")
		)
		(pad "2" smd rect
			(at -0.7366 0 90)
			(size 0.7112 0.8128)
			(layers "B.Cu" "B.Mask" "B.Paste")
			(net "GND")
		)
	)
	(footprint ""
		(layer "B.Cu")
		(at 380.990602 -236.40796 180)
		(property "Reference" "L5"
			(at 0 0 0)
			(layer "B.SilkS")
			(hide yes)
			(effects
				(font
					(size 1.27 1.27)
				)
				(justify mirror)
			)
		)
		(property "Value" ""
			(at 0 0 0)
			(layer "B.Fab")
			(effects
				(font
					(size 1.27 1.27)
				)
				(justify mirror)
			)
		)
		(duplicate_pad_numbers_are_jumpers no)
		(fp_line
			(start 1.27 0.5842)
			(end 1.27 -0.5842)
			(stroke
				(width 0.1524)
				(type default)
			)
			(layer "B.SilkS")
		)
		(fp_line
			(start 1.27 -0.5588)
			(end 1.27 -0.5842)
			(stroke
				(width 0.1524)
				(type default)
			)
			(layer "B.SilkS")
		)
		(fp_line
			(start 1.27 -0.5842)
			(end -1.27 -0.5842)
			(stroke
				(width 0.1524)
				(type default)
			)
			(layer "B.SilkS")
		)
		(fp_line
			(start -1.27 0.5842)
			(end 1.27 0.5842)
			(stroke
				(width 0.1524)
				(type default)
			)
			(layer "B.SilkS")
		)
		(fp_line
			(start -1.27 0.5842)
			(end -1.27 -0.5842)
			(stroke
				(width 0.1524)
				(type default)
			)
			(layer "B.SilkS")
		)
		(fp_line
			(start 1.194308 0.406654)
			(end 1.194308 -0.406654)
			(stroke
				(width 0.1)
				(type default)
			)
			(layer "B.Fab")
		)
		(fp_line
			(start 1.194308 -0.406654)
			(end 0.9144 -0.406654)
			(stroke
				(width 0.1)
				(type default)
			)
			(layer "B.Fab")
		)
		(fp_line
			(start 0.9144 0.508)
			(end 0.9144 0.406654)
			(stroke
				(width 0.1)
				(type default)
			)
			(layer "B.Fab")
		)
		(fp_line
			(start 0.9144 0.406654)
			(end 1.194308 0.406654)
			(stroke
				(width 0.1)
				(type default)
			)
			(layer "B.Fab")
		)
		(fp_line
			(start 0.9144 -0.406654)
			(end 0.9144 -0.508)
			(stroke
				(width 0.1)
				(type default)
			)
			(layer "B.Fab")
		)
		(fp_line
			(start 0.9144 -0.508)
			(end -0.9144 -0.508)
			(stroke
				(width 0.1)
				(type default)
			)
			(layer "B.Fab")
		)
		(fp_line
			(start -0.9144 0.508)
			(end 0.9144 0.508)
			(stroke
				(width 0.1)
				(type default)
			)
			(layer "B.Fab")
		)
		(fp_line
			(start -0.9144 0.4064)
			(end -0.9144 0.508)
			(stroke
				(width 0.1)
				(type default)
			)
			(layer "B.Fab")
		)
		(fp_line
			(start -0.9144 -0.406654)
			(end -1.1938 -0.406654)
			(stroke
				(width 0.1)
				(type default)
			)
			(layer "B.Fab")
		)
		(fp_line
			(start -0.9144 -0.508)
			(end -0.9144 -0.406654)
			(stroke
				(width 0.1)
				(type default)
			)
			(layer "B.Fab")
		)
		(fp_line
			(start -1.1938 0.4064)
			(end -0.9144 0.4064)
			(stroke
				(width 0.1)
				(type default)
			)
			(layer "B.Fab")
		)
		(fp_line
			(start -1.1938 -0.406654)
			(end -1.1938 0.4064)
			(stroke
				(width 0.1)
				(type default)
			)
			(layer "B.Fab")
		)
		(pad "1" smd rect
			(at 0.7366 0 90)
			(size 0.7112 0.8128)
			(layers "B.Cu" "B.Mask" "B.Paste")
			(net "P3V3_AUX")
		)
		(pad "2" smd rect
			(at -0.7366 0 90)
			(size 0.7112 0.8128)
			(layers "B.Cu" "B.Mask" "B.Paste")
			(net "P3V3_SDB_VPHY")
		)
	)
	(footprint ""
		(layer "B.Cu")
		(at 193.641726 -104.120696 180)
		(property "Reference" "R168"
			(at 0 0 0)
			(layer "B.SilkS")
			(hide yes)
			(effects
				(font
					(size 1.27 1.27)
				)
				(justify mirror)
			)
		)
		(property "Value" ""
			(at 0 0 0)
			(layer "B.Fab")
			(effects
				(font
					(size 1.27 1.27)
				)
				(justify mirror)
			)
		)
		(duplicate_pad_numbers_are_jumpers no)
		(fp_line
			(start 0.7874 0.4064)
			(end 0.7874 -0.4064)
			(stroke
				(width 0.1524)
				(type default)
			)
			(layer "B.SilkS")
		)
		(fp_line
			(start 0.7874 -0.4064)
			(end -0.7874 -0.4064)
			(stroke
				(width 0.1524)
				(type default)
			)
			(layer "B.SilkS")
		)
		(fp_line
			(start -0.7874 0.4064)
			(end 0.7874 0.4064)
			(stroke
				(width 0.1524)
				(type default)
			)
			(layer "B.SilkS")
		)
		(fp_line
			(start -0.7874 -0.4064)
			(end -0.7874 0.4064)
			(stroke
				(width 0.1524)
				(type default)
			)
			(layer "B.SilkS")
		)
		(fp_line
			(start 0.67945 0.3048)
			(end 0.67945 -0.305054)
			(stroke
				(width 0.1)
				(type default)
			)
			(layer "B.Fab")
		)
		(fp_line
			(start 0.67945 -0.305054)
			(end 0.12065 -0.305054)
			(stroke
				(width 0.1)
				(type default)
			)
			(layer "B.Fab")
		)
		(fp_line
			(start 0.12065 0.3048)
			(end 0.67945 0.3048)
			(stroke
				(width 0.1)
				(type default)
			)
			(layer "B.Fab")
		)
		(fp_line
			(start 0.12065 0.2794)
			(end 0.12065 0.3048)
			(stroke
				(width 0.1)
				(type default)
			)
			(layer "B.Fab")
		)
		(fp_line
			(start 0.12065 -0.2794)
			(end -0.12065 -0.2794)
			(stroke
				(width 0.1)
				(type default)
			)
			(layer "B.Fab")
		)
		(fp_line
			(start 0.12065 -0.305054)
			(end 0.12065 -0.2794)
			(stroke
				(width 0.1)
				(type default)
			)
			(layer "B.Fab")
		)
		(fp_line
			(start -0.120396 0.3048)
			(end -0.120396 0.2794)
			(stroke
				(width 0.1)
				(type default)
			)
			(layer "B.Fab")
		)
		(fp_line
			(start -0.120396 0.2794)
			(end 0.12065 0.2794)
			(stroke
				(width 0.1)
				(type default)
			)
			(layer "B.Fab")
		)
		(fp_line
			(start -0.12065 -0.2794)
			(end -0.12065 -0.3048)
			(stroke
				(width 0.1)
				(type default)
			)
			(layer "B.Fab")
		)
		(fp_line
			(start -0.12065 -0.3048)
			(end -0.67945 -0.3048)
			(stroke
				(width 0.1)
				(type default)
			)
			(layer "B.Fab")
		)
		(fp_line
			(start -0.67945 0.3048)
			(end -0.120396 0.3048)
			(stroke
				(width 0.1)
				(type default)
			)
			(layer "B.Fab")
		)
		(fp_line
			(start -0.67945 -0.3048)
			(end -0.67945 0.3048)
			(stroke
				(width 0.1)
				(type default)
			)
			(layer "B.Fab")
		)
		(pad "1" smd circle
			(at 0.40005 0)
			(size 0 0)
			(layers "B.Cu" "B.Mask" "B.Paste")
			(net "NCSI_NIC3_CRS_DV")
		)
		(pad "2" smd circle
			(at -0.40005 0)
			(size 0 0)
			(layers "B.Cu" "B.Mask" "B.Paste")
			(net "GND")
		)
	)
)
